(kicad_pcb
	(version 20260206)
	(generator "pcbnew")
	(generator_version "10.0")
	(general
		(thickness 1.6)
		(legacy_teardrops no)
	)
	(paper "A4")
	(title_block
		(title "netronome-mezz — pcbd0082-001_rev01_jul9_a.brd")
		(comment 1 "Open CloudServer (Microsoft) / footprints 431-435 of 714")
	)
	(layers
		(0 "F.Cu" signal "TOP")
		(4 "In1.Cu" signal "02_GND")
		(6 "In2.Cu" signal "03_SIG")
		(8 "In3.Cu" signal "04_SIG")
		(10 "In4.Cu" signal "05_GND")
		(12 "In5.Cu" signal "06_PWR1")
		(14 "In6.Cu" signal "07_SIG")
		(16 "In7.Cu" signal "08_SIG")
		(18 "In8.Cu" signal "09_GND")
		(2 "B.Cu" signal "BOTTOM")
		(9 "F.Adhes" user "F.Adhesive")
		(11 "B.Adhes" user "B.Adhesive")
		(13 "F.Paste" user "Package Geometry/Pastemask Top")
		(15 "B.Paste" user "Package Geometry/Pastemask Bottom")
		(5 "F.SilkS" user "Ref Des/Silkscreen Top")
		(7 "B.SilkS" user "Ref Des/Silkscreen Bottom")
		(1 "F.Mask" user "Board Geometry/Soldermask Top")
		(3 "B.Mask" user "Board Geometry/Soldermask Bottom")
		(17 "Dwgs.User" user "User.Drawings")
		(19 "Cmts.User" user "User.Comments")
		(21 "Eco1.User" user "User.Eco1")
		(23 "Eco2.User" user "User.Eco2")
		(25 "Edge.Cuts" user "Board Geometry/Outline")
		(27 "Margin" user)
		(31 "F.CrtYd" user "Package Geometry/Place Bound Top")
		(29 "B.CrtYd" user "Package Geometry/Place Bound Bottom")
		(35 "F.Fab" user "Ref Des/Assembly Top")
		(33 "B.Fab" user "Ref Des/Assembly Bottom")
		(45 "User.4" user "COMPVAL_TYPE_BOTTOM")
	)
	(footprint ""
		(layer "B.Cu")
		(at 5.207 8.001)
		(property "Reference" "TP27"
			(at 1.49733 0.508 270)
			(unlocked yes)
			(layer "B.SilkS")
			(effects
				(font
					(size 0.7874 0.5842)
					(thickness 0.127)
				)
				(justify left mirror)
			)
		)
		(property "Value" "*"
			(at 0.4826 -0.14732 0)
			(unlocked yes)
			(layer "B.Fab")
			(hide yes)
			(effects
				(font
					(size 1.27 0.9652)
					(thickness 0.000001)
				)
				(justify left mirror)
			)
		)
		(property "Device Type" "TP_SMALL"
			(at 0.4826 -0.14732 0)
			(unlocked yes)
			(layer "B.Fab")
			(hide yes)
			(effects
				(font
					(size 1.27 0.9652)
					(thickness 0.000001)
				)
				(justify left mirror)
			)
		)
		(duplicate_pad_numbers_are_jumpers no)
		(fp_line
			(start -0.8636 -0.8636)
			(end 0.8636 -0.8636)
			(stroke
				(width 0.1524)
				(type default)
			)
			(layer "B.SilkS")
		)
		(fp_line
			(start -0.8636 0.8636)
			(end -0.8636 -0.8636)
			(stroke
				(width 0.1524)
				(type default)
			)
			(layer "B.SilkS")
		)
		(fp_line
			(start 0.8636 -0.8636)
			(end 0.8636 0.8636)
			(stroke
				(width 0.1524)
				(type default)
			)
			(layer "B.SilkS")
		)
		(fp_line
			(start 0.8636 0.8636)
			(end -0.8636 0.8636)
			(stroke
				(width 0.1524)
				(type default)
			)
			(layer "B.SilkS")
		)
		(fp_poly
			(pts
				(xy 0.635 -0.635) (xy 0.635 0.635) (xy -0.635 0.635) (xy -0.635 -0.635)
			)
			(stroke
				(width 0)
				(type default)
			)
			(fill no)
			(layer "B.CrtYd")
		)
		(pad "1" smd rect
			(at 0 0 180)
			(size 1.27 1.27)
			(layers "B.Cu" "B.Mask" "B.Paste")
			(net "PGRM_JTAG_TCK")
		)
	)
	(footprint ""
		(layer "B.Cu")
		(at 63.119 41.0845)
		(property "Reference" "R116"
			(at 0.86233 2.6035 270)
			(unlocked yes)
			(layer "B.SilkS")
			(effects
				(font
					(size 0.7874 0.5842)
					(thickness 0.127)
				)
				(justify left mirror)
			)
		)
		(property "Value" "2.2"
			(at 0.148158 1.7526 270)
			(unlocked yes)
			(layer "B.Fab")
			(hide yes)
			(effects
				(font
					(size 1.27 0.9652)
					(thickness 0.000001)
				)
				(justify left mirror)
			)
		)
		(property "Device Type" "REST0145"
			(at 0.148158 1.7526 270)
			(unlocked yes)
			(layer "B.Fab")
			(hide yes)
			(effects
				(font
					(size 1.27 0.9652)
					(thickness 0.000001)
				)
				(justify left mirror)
			)
		)
		(duplicate_pad_numbers_are_jumpers no)
		(fp_circle
			(center 0 0)
			(end 0.127 0)
			(stroke
				(width 0.2032)
				(type default)
			)
			(fill no)
			(layer "B.SilkS")
		)
		(fp_poly
			(pts
				(xy -0.7874 -1.6637) (xy 0.7874 -1.6637) (xy 0.7874 1.6637) (xy -0.7874 1.6637)
			)
			(stroke
				(width 0)
				(type default)
			)
			(fill no)
			(layer "B.CrtYd")
		)
		(fp_line
			(start -0.4064 -0.8128)
			(end -0.4064 0.8128)
			(stroke
				(width 0.0254)
				(type default)
			)
			(layer "B.Fab")
		)
		(fp_line
			(start -0.4064 0.8128)
			(end 0.4064 0.8128)
			(stroke
				(width 0.0254)
				(type default)
			)
			(layer "B.Fab")
		)
		(fp_line
			(start 0.4064 -0.8128)
			(end -0.4064 -0.8128)
			(stroke
				(width 0.0254)
				(type default)
			)
			(layer "B.Fab")
		)
		(fp_line
			(start 0.4064 0.8128)
			(end 0.4064 -0.8128)
			(stroke
				(width 0.0254)
				(type default)
			)
			(layer "B.Fab")
		)
		(pad "1" smd rect
			(at 0 -0.8001 180)
			(size 0.762 0.9652)
			(layers "B.Cu" "B.Mask" "B.Paste")
			(net "10N2224")
		)
		(pad "2" smd rect
			(at 0 0.8001 180)
			(size 0.762 0.9652)
			(layers "B.Cu" "B.Mask" "B.Paste")
			(net "L_1_CORE_PHASE")
		)
		(zone
			(layer "B.Cu")
			(hatch none 0.5)
			(connect_pads
				(clearance 0)
			)
			(min_thickness 0.25)
			(keepout
				(tracks not_allowed)
				(vias allowed)
				(pads allowed)
				(copperpour not_allowed)
				(footprints allowed)
			)
			(placement
				(enabled no)
				(sheetname "")
			)
			(fill
				(thermal_gap 0.5)
				(thermal_bridge_width 0.5)
				(island_removal_mode 0)
			)
			(polygon
				(pts
					(xy 63.1825 40.8305) (xy 63.0555 40.8305) (xy 63.0555 41.3385) (xy 63.1825 41.3385)
				)
			)
		)
	)
	(footprint ""
		(layer "B.Cu")
		(at 40.259 39.751)
		(property "Reference" "TP31"
			(at 1.49733 0.254 270)
			(unlocked yes)
			(layer "B.SilkS")
			(effects
				(font
					(size 0.7874 0.5842)
					(thickness 0.127)
				)
				(justify left mirror)
			)
		)
		(property "Value" "*"
			(at 0.4826 -0.14732 0)
			(unlocked yes)
			(layer "B.Fab")
			(hide yes)
			(effects
				(font
					(size 1.27 0.9652)
					(thickness 0.000001)
				)
				(justify left mirror)
			)
		)
		(property "Device Type" "TP_SMALL"
			(at 0.4826 -0.14732 0)
			(unlocked yes)
			(layer "B.Fab")
			(hide yes)
			(effects
				(font
					(size 1.27 0.9652)
					(thickness 0.000001)
				)
				(justify left mirror)
			)
		)
		(duplicate_pad_numbers_are_jumpers no)
		(fp_line
			(start -0.8636 -0.8636)
			(end 0.8636 -0.8636)
			(stroke
				(width 0.1524)
				(type default)
			)
			(layer "B.SilkS")
		)
		(fp_line
			(start -0.8636 0.8636)
			(end -0.8636 -0.8636)
			(stroke
				(width 0.1524)
				(type default)
			)
			(layer "B.SilkS")
		)
		(fp_line
			(start 0.8636 -0.8636)
			(end 0.8636 0.8636)
			(stroke
				(width 0.1524)
				(type default)
			)
			(layer "B.SilkS")
		)
		(fp_line
			(start 0.8636 0.8636)
			(end -0.8636 0.8636)
			(stroke
				(width 0.1524)
				(type default)
			)
			(layer "B.SilkS")
		)
		(fp_poly
			(pts
				(xy 0.635 -0.635) (xy 0.635 0.635) (xy -0.635 0.635) (xy -0.635 -0.635)
			)
			(stroke
				(width 0)
				(type default)
			)
			(fill no)
			(layer "B.CrtYd")
		)
		(pad "1" smd rect
			(at 0 0 180)
			(size 1.27 1.27)
			(layers "B.Cu" "B.Mask" "B.Paste")
			(net "GL_PHASE2")
		)
	)
	(footprint ""
		(layer "B.Cu")
		(at 52.48656 0.762 180)
		(property "Reference" "C148"
			(at 0.145212 0.8763 270)
			(unlocked yes)
			(layer "B.SilkS")
			(effects
				(font
					(size 0.7874 0.5842)
					(thickness 0.127)
				)
				(justify left mirror)
			)
		)
		(property "Value" "0.22UF"
			(at 0.091846 0.2921 90)
			(unlocked yes)
			(layer "B.Fab")
			(hide yes)
			(effects
				(font
					(size 0.7874 0.5842)
					(thickness 0.2032)
				)
				(justify left mirror)
			)
		)
		(property "Device Type" "CAPC0062"
			(at 0.091846 0.2921 90)
			(unlocked yes)
			(layer "B.Fab")
			(hide yes)
			(effects
				(font
					(size 0.7874 0.5842)
					(thickness 0.2032)
				)
				(justify left mirror)
			)
		)
		(duplicate_pad_numbers_are_jumpers no)
		(fp_poly
			(pts
				(xy -0.635 1.0668) (xy -0.635 -1.0668) (xy 0.635 -1.0668) (xy 0.635 1.0668)
			)
			(stroke
				(width 0)
				(type default)
			)
			(fill no)
			(layer "B.CrtYd")
		)
		(fp_line
			(start 0.254 0.508)
			(end 0.254 -0.508)
			(stroke
				(width 0.0254)
				(type default)
			)
			(layer "B.Fab")
		)
		(fp_line
			(start 0.254 -0.508)
			(end -0.254 -0.508)
			(stroke
				(width 0.0254)
				(type default)
			)
			(layer "B.Fab")
		)
		(fp_line
			(start -0.254 0.508)
			(end 0.254 0.508)
			(stroke
				(width 0.0254)
				(type default)
			)
			(layer "B.Fab")
		)
		(fp_line
			(start -0.254 -0.508)
			(end -0.254 0.508)
			(stroke
				(width 0.0254)
				(type default)
			)
			(layer "B.Fab")
		)
		(pad "1" smd rect
			(at 0 -0.4191)
			(size 0.508 0.5334)
			(layers "B.Cu" "B.Mask" "B.Paste")
			(net "_NFP_PCIE0_PER5_N")
		)
		(pad "2" smd rect
			(at 0 0.4191)
			(size 0.508 0.5334)
			(layers "B.Cu" "B.Mask" "B.Paste")
			(net "NFP_PCIE0_PER5_N")
		)
		(zone
			(layer "B.Cu")
			(hatch none 0.5)
			(connect_pads
				(clearance 0)
			)
			(min_thickness 0.25)
			(keepout
				(tracks not_allowed)
				(vias allowed)
				(pads allowed)
				(copperpour not_allowed)
				(footprints allowed)
			)
			(placement
				(enabled no)
				(sheetname "")
			)
			(fill
				(thermal_gap 0.5)
				(thermal_bridge_width 0.5)
				(island_removal_mode 0)
			)
			(polygon
				(pts
					(xy 52.51196 0.7874) (xy 52.51196 0.7366) (xy 52.46116 0.7366) (xy 52.46116 0.7874)
				)
			)
		)
	)
	(footprint ""
		(layer "B.Cu")
		(at 56.388 0.762 180)
		(property "Reference" "C160"
			(at 0.145212 0.8763 270)
			(unlocked yes)
			(layer "B.SilkS")
			(effects
				(font
					(size 0.7874 0.5842)
					(thickness 0.127)
				)
				(justify left mirror)
			)
		)
		(property "Value" "0.22UF"
			(at 0.091846 0.2921 90)
			(unlocked yes)
			(layer "B.Fab")
			(hide yes)
			(effects
				(font
					(size 0.7874 0.5842)
					(thickness 0.2032)
				)
				(justify left mirror)
			)
		)
		(property "Device Type" "CAPC0062"
			(at 0.091846 0.2921 90)
			(unlocked yes)
			(layer "B.Fab")
			(hide yes)
			(effects
				(font
					(size 0.7874 0.5842)
					(thickness 0.2032)
				)
				(justify left mirror)
			)
		)
		(duplicate_pad_numbers_are_jumpers no)
		(fp_poly
			(pts
				(xy -0.635 1.0668) (xy -0.635 -1.0668) (xy 0.635 -1.0668) (xy 0.635 1.0668)
			)
			(stroke
				(width 0)
				(type default)
			)
			(fill no)
			(layer "B.CrtYd")
		)
		(fp_line
			(start 0.254 0.508)
			(end 0.254 -0.508)
			(stroke
				(width 0.0254)
				(type default)
			)
			(layer "B.Fab")
		)
		(fp_line
			(start 0.254 -0.508)
			(end -0.254 -0.508)
			(stroke
				(width 0.0254)
				(type default)
			)
			(layer "B.Fab")
		)
		(fp_line
			(start -0.254 0.508)
			(end 0.254 0.508)
			(stroke
				(width 0.0254)
				(type default)
			)
			(layer "B.Fab")
		)
		(fp_line
			(start -0.254 -0.508)
			(end -0.254 0.508)
			(stroke
				(width 0.0254)
				(type default)
			)
			(layer "B.Fab")
		)
		(pad "1" smd rect
			(at 0 -0.4191)
			(size 0.508 0.5334)
			(layers "B.Cu" "B.Mask" "B.Paste")
			(net "_NFP_PCIE0_PER3_N")
		)
		(pad "2" smd rect
			(at 0 0.4191)
			(size 0.508 0.5334)
			(layers "B.Cu" "B.Mask" "B.Paste")
			(net "NFP_PCIE0_PER3_N")
		)
		(zone
			(layer "B.Cu")
			(hatch none 0.5)
			(connect_pads
				(clearance 0)
			)
			(min_thickness 0.25)
			(keepout
				(tracks not_allowed)
				(vias allowed)
				(pads allowed)
				(copperpour not_allowed)
				(footprints allowed)
			)
			(placement
				(enabled no)
				(sheetname "")
			)
			(fill
				(thermal_gap 0.5)
				(thermal_bridge_width 0.5)
				(island_removal_mode 0)
			)
			(polygon
				(pts
					(xy 56.4134 0.7874) (xy 56.4134 0.7366) (xy 56.3626 0.7366) (xy 56.3626 0.7874)
				)
			)
		)
	)
)
